(kicad_pcb
	(version 20260206)
	(generator "pcbnew")
	(generator_version "10.0")
	(general
		(thickness 1.6)
		(legacy_teardrops no)
	)
	(paper "A4")
	(title_block
		(title "v1-chassis-manager — T6M_CM_d_v01_1031_1645.brd")
		(comment 1 "Open CloudServer (Microsoft) / footprints 972-981 of 2512")
	)
	(layers
		(0 "F.Cu" signal "TOP")
		(4 "In1.Cu" signal "GND1")
		(6 "In2.Cu" signal "IN1")
		(8 "In3.Cu" signal "VCC1")
		(10 "In4.Cu" signal "VCC2")
		(12 "In5.Cu" signal "GND2")
		(14 "In6.Cu" signal "IN2")
		(16 "In7.Cu" signal "IN3")
		(18 "In8.Cu" signal "GND3")
		(2 "B.Cu" signal "BOTTOM")
		(9 "F.Adhes" user "F.Adhesive")
		(11 "B.Adhes" user "B.Adhesive")
		(13 "F.Paste" user "Package Geometry/Pastemask Top")
		(15 "B.Paste" user "Package Geometry/Pastemask Bottom")
		(5 "F.SilkS" user "Ref Des/Silkscreen Top")
		(7 "B.SilkS" user "Ref Des/Silkscreen Bottom")
		(1 "F.Mask" user "Board Geometry/Soldermask Top")
		(3 "B.Mask" user "Board Geometry/Soldermask Bottom")
		(17 "Dwgs.User" user "User.Drawings")
		(19 "Cmts.User" user "User.Comments")
		(21 "Eco1.User" user "User.Eco1")
		(23 "Eco2.User" user "User.Eco2")
		(25 "Edge.Cuts" user "Board Geometry/Outline")
		(27 "Margin" user)
		(31 "F.CrtYd" user "Package Geometry/Place Bound Top")
		(29 "B.CrtYd" user "Package Geometry/Place Bound Bottom")
		(35 "F.Fab" user "Ref Des/Assembly Top")
		(33 "B.Fab" user "Ref Des/Assembly Bottom")
	)
	(footprint ""
		(layer "F.Cu")
		(at 144.942052 -142.19555)
		(property "Reference" "R233"
			(at -1.015746 17.738344 0)
			(unlocked yes)
			(layer "F.SilkS")
			(effects
				(font
					(size 0.7874 0.5842)
					(thickness 0.1524)
				)
				(justify left)
			)
		)
		(property "Value" ""
			(at 0 0 0)
			(layer "F.Fab")
			(effects
				(font
					(size 1.27 1.27)
				)
			)
		)
		(duplicate_pad_numbers_are_jumpers no)
		(fp_line
			(start -0.7874 -0.4064)
			(end 0.7874 -0.4064)
			(stroke
				(width 0.1524)
				(type default)
			)
			(layer "F.SilkS")
		)
		(fp_line
			(start -0.7874 0.4064)
			(end -0.7874 -0.4064)
			(stroke
				(width 0.1524)
				(type default)
			)
			(layer "F.SilkS")
		)
		(fp_line
			(start 0.7874 -0.4064)
			(end 0.7874 0.4064)
			(stroke
				(width 0.1524)
				(type default)
			)
			(layer "F.SilkS")
		)
		(fp_line
			(start 0.7874 0.4064)
			(end -0.7874 0.4064)
			(stroke
				(width 0.1524)
				(type default)
			)
			(layer "F.SilkS")
		)
		(fp_poly
			(pts
				(xy -0.508 0.2794) (xy -0.508 0.2286) (xy -0.635 0.2286) (xy -0.635 -0.254) (xy -0.5334 -0.254)
				(xy -0.5334 -0.2794) (xy 0.5334 -0.2794) (xy 0.5334 -0.254) (xy 0.635 -0.254) (xy 0.635 0.254) (xy 0.5334 0.254)
				(xy 0.5334 0.2794)
			)
			(stroke
				(width 0)
				(type default)
			)
			(fill no)
			(layer "F.CrtYd")
		)
		(pad "1" smd rect
			(at 0.40005 0)
			(size 0.4572 0.508)
			(layers "F.Cu" "F.Mask" "F.Paste")
			(net "SMB_CPU_NODE1_BMC_DAT")
		)
		(pad "2" smd rect
			(at -0.40005 0)
			(size 0.4572 0.508)
			(layers "F.Cu" "F.Mask" "F.Paste")
			(net "PCIE_SW_I2C_SDA")
		)
	)
	(footprint ""
		(layer "F.Cu")
		(at 184.3786 -184.8612)
		(property "Reference" "R1271"
			(at 9.4234 16.96847 0)
			(unlocked yes)
			(layer "F.SilkS")
			(effects
				(font
					(size 0.7874 0.5842)
					(thickness 0.1524)
				)
				(justify left)
			)
		)
		(property "Value" ""
			(at 0 0 0)
			(layer "F.Fab")
			(effects
				(font
					(size 1.27 1.27)
				)
			)
		)
		(duplicate_pad_numbers_are_jumpers no)
		(fp_line
			(start -0.7874 -0.4064)
			(end 0.7874 -0.4064)
			(stroke
				(width 0.1524)
				(type default)
			)
			(layer "F.SilkS")
		)
		(fp_line
			(start -0.7874 0.4064)
			(end -0.7874 -0.4064)
			(stroke
				(width 0.1524)
				(type default)
			)
			(layer "F.SilkS")
		)
		(fp_line
			(start 0.7874 -0.4064)
			(end 0.7874 0.4064)
			(stroke
				(width 0.1524)
				(type default)
			)
			(layer "F.SilkS")
		)
		(fp_line
			(start 0.7874 0.4064)
			(end -0.7874 0.4064)
			(stroke
				(width 0.1524)
				(type default)
			)
			(layer "F.SilkS")
		)
		(fp_poly
			(pts
				(xy -0.508 0.2794) (xy -0.508 0.2286) (xy -0.635 0.2286) (xy -0.635 -0.254) (xy -0.5334 -0.254)
				(xy -0.5334 -0.2794) (xy 0.5334 -0.2794) (xy 0.5334 -0.254) (xy 0.635 -0.254) (xy 0.635 0.254) (xy 0.5334 0.254)
				(xy 0.5334 0.2794)
			)
			(stroke
				(width 0)
				(type default)
			)
			(fill no)
			(layer "F.CrtYd")
		)
		(pad "1" smd rect
			(at 0.40005 0)
			(size 0.4572 0.508)
			(layers "F.Cu" "F.Mask" "F.Paste")
			(net "POWER_SW3_PWR_CTR_12V")
		)
		(pad "2" smd rect
			(at -0.40005 0)
			(size 0.4572 0.508)
			(layers "F.Cu" "F.Mask" "F.Paste")
			(net "POWER_SW3_PWR_CTR_12V_R")
		)
	)
	(footprint ""
		(layer "F.Cu")
		(at 34.456878 -11.033506 180)
		(property "Reference" "PR36"
			(at 10.748772 0.014478 0)
			(unlocked yes)
			(layer "F.SilkS")
			(effects
				(font
					(size 0.7874 0.5842)
					(thickness 0.1524)
				)
				(justify left)
			)
		)
		(property "Value" ""
			(at 0 0 180)
			(layer "F.Fab")
			(effects
				(font
					(size 1.27 1.27)
				)
			)
		)
		(duplicate_pad_numbers_are_jumpers no)
		(fp_line
			(start 0.7874 0.4064)
			(end -0.7874 0.4064)
			(stroke
				(width 0.1524)
				(type default)
			)
			(layer "F.SilkS")
		)
		(fp_line
			(start 0.7874 -0.4064)
			(end 0.7874 0.4064)
			(stroke
				(width 0.1524)
				(type default)
			)
			(layer "F.SilkS")
		)
		(fp_line
			(start -0.7874 0.4064)
			(end -0.7874 -0.4064)
			(stroke
				(width 0.1524)
				(type default)
			)
			(layer "F.SilkS")
		)
		(fp_line
			(start -0.7874 -0.4064)
			(end 0.7874 -0.4064)
			(stroke
				(width 0.1524)
				(type default)
			)
			(layer "F.SilkS")
		)
		(fp_poly
			(pts
				(xy -0.508 0.2794) (xy -0.508 0.2286) (xy -0.635 0.2286) (xy -0.635 -0.254) (xy -0.5334 -0.254)
				(xy -0.5334 -0.2794) (xy 0.5334 -0.2794) (xy 0.5334 -0.254) (xy 0.635 -0.254) (xy 0.635 0.254) (xy 0.5334 0.254)
				(xy 0.5334 0.2794)
			)
			(stroke
				(width 0)
				(type default)
			)
			(fill no)
			(layer "F.CrtYd")
		)
		(pad "1" smd rect
			(at 0.40005 0 180)
			(size 0.4572 0.508)
			(layers "F.Cu" "F.Mask" "F.Paste")
			(net "GND")
		)
		(pad "2" smd rect
			(at -0.40005 0 180)
			(size 0.4572 0.508)
			(layers "F.Cu" "F.Mask" "F.Paste")
			(net "PV_VDDR_NODE1_V1")
		)
	)
	(footprint ""
		(layer "F.Cu")
		(at 170.176698 -12.474194 90)
		(property "Reference" "R1199"
			(at -0.940054 -0.998728 90)
			(unlocked yes)
			(layer "F.SilkS")
			(effects
				(font
					(size 0.7874 0.5842)
					(thickness 0.1524)
				)
				(justify left)
			)
		)
		(property "Value" ""
			(at 0 0 90)
			(layer "F.Fab")
			(effects
				(font
					(size 1.27 1.27)
				)
			)
		)
		(duplicate_pad_numbers_are_jumpers no)
		(fp_line
			(start 0.7874 -0.4064)
			(end 0.7874 0.4064)
			(stroke
				(width 0.1524)
				(type default)
			)
			(layer "F.SilkS")
		)
		(fp_line
			(start -0.7874 -0.4064)
			(end 0.7874 -0.4064)
			(stroke
				(width 0.1524)
				(type default)
			)
			(layer "F.SilkS")
		)
		(fp_line
			(start 0.7874 0.4064)
			(end -0.7874 0.4064)
			(stroke
				(width 0.1524)
				(type default)
			)
			(layer "F.SilkS")
		)
		(fp_line
			(start -0.7874 0.4064)
			(end -0.7874 -0.4064)
			(stroke
				(width 0.1524)
				(type default)
			)
			(layer "F.SilkS")
		)
		(fp_poly
			(pts
				(xy -0.508 0.2794) (xy -0.508 0.2286) (xy -0.635 0.2286) (xy -0.635 -0.254) (xy -0.5334 -0.254)
				(xy -0.5334 -0.2794) (xy 0.5334 -0.2794) (xy 0.5334 -0.254) (xy 0.635 -0.254) (xy 0.635 0.254) (xy 0.5334 0.254)
				(xy 0.5334 0.2794)
			)
			(stroke
				(width 0)
				(type default)
			)
			(fill no)
			(layer "F.CrtYd")
		)
		(pad "1" smd rect
			(at 0.40005 0 90)
			(size 0.4572 0.508)
			(layers "F.Cu" "F.Mask" "F.Paste")
			(net "SIO_JTAG_CPLD3_TDO")
		)
		(pad "2" smd rect
			(at -0.40005 0 90)
			(size 0.4572 0.508)
			(layers "F.Cu" "F.Mask" "F.Paste")
			(net "JTAG_CPLD3_TDO")
		)
	)
	(footprint ""
		(layer "F.Cu")
		(at 106.170476 -170.965876 180)
		(property "Reference" "R763"
			(at -1.206754 -0.19431 0)
			(unlocked yes)
			(layer "F.SilkS")
			(effects
				(font
					(size 0.7874 0.5842)
					(thickness 0.1524)
				)
				(justify left)
			)
		)
		(property "Value" ""
			(at 0 0 180)
			(layer "F.Fab")
			(effects
				(font
					(size 1.27 1.27)
				)
			)
		)
		(duplicate_pad_numbers_are_jumpers no)
		(fp_line
			(start 0.7874 0.4064)
			(end -0.7874 0.4064)
			(stroke
				(width 0.1524)
				(type default)
			)
			(layer "F.SilkS")
		)
		(fp_line
			(start 0.7874 -0.4064)
			(end 0.7874 0.4064)
			(stroke
				(width 0.1524)
				(type default)
			)
			(layer "F.SilkS")
		)
		(fp_line
			(start -0.7874 0.4064)
			(end -0.7874 -0.4064)
			(stroke
				(width 0.1524)
				(type default)
			)
			(layer "F.SilkS")
		)
		(fp_line
			(start -0.7874 -0.4064)
			(end 0.7874 -0.4064)
			(stroke
				(width 0.1524)
				(type default)
			)
			(layer "F.SilkS")
		)
		(fp_poly
			(pts
				(xy -0.508 0.2794) (xy -0.508 0.2286) (xy -0.635 0.2286) (xy -0.635 -0.254) (xy -0.5334 -0.254)
				(xy -0.5334 -0.2794) (xy 0.5334 -0.2794) (xy 0.5334 -0.254) (xy 0.635 -0.254) (xy 0.635 0.254) (xy 0.5334 0.254)
				(xy 0.5334 0.2794)
			)
			(stroke
				(width 0)
				(type default)
			)
			(fill no)
			(layer "F.CrtYd")
		)
		(pad "1" smd rect
			(at 0.40005 0 180)
			(size 0.4572 0.508)
			(layers "F.Cu" "F.Mask" "F.Paste")
			(net "FNACTRL1_ADD")
		)
		(pad "2" smd rect
			(at -0.40005 0 180)
			(size 0.4572 0.508)
			(layers "F.Cu" "F.Mask" "F.Paste")
			(net "GND")
		)
	)
	(footprint ""
		(layer "F.Cu")
		(at 79.66456 -151.70277)
		(property "Reference" "R1082"
			(at -0.218948 5.82295 90)
			(unlocked yes)
			(layer "F.SilkS")
			(effects
				(font
					(size 0.7874 0.5842)
					(thickness 0.1524)
				)
				(justify left)
			)
		)
		(property "Value" ""
			(at 0 0 0)
			(layer "F.Fab")
			(effects
				(font
					(size 1.27 1.27)
				)
			)
		)
		(duplicate_pad_numbers_are_jumpers no)
		(fp_line
			(start -0.7874 -0.4064)
			(end 0.7874 -0.4064)
			(stroke
				(width 0.1524)
				(type default)
			)
			(layer "F.SilkS")
		)
		(fp_line
			(start -0.7874 0.4064)
			(end -0.7874 -0.4064)
			(stroke
				(width 0.1524)
				(type default)
			)
			(layer "F.SilkS")
		)
		(fp_line
			(start 0.7874 -0.4064)
			(end 0.7874 0.4064)
			(stroke
				(width 0.1524)
				(type default)
			)
			(layer "F.SilkS")
		)
		(fp_line
			(start 0.7874 0.4064)
			(end -0.7874 0.4064)
			(stroke
				(width 0.1524)
				(type default)
			)
			(layer "F.SilkS")
		)
		(fp_poly
			(pts
				(xy -0.508 0.2794) (xy -0.508 0.2286) (xy -0.635 0.2286) (xy -0.635 -0.254) (xy -0.5334 -0.254)
				(xy -0.5334 -0.2794) (xy 0.5334 -0.2794) (xy 0.5334 -0.254) (xy 0.635 -0.254) (xy 0.635 0.254) (xy 0.5334 0.254)
				(xy 0.5334 0.2794)
			)
			(stroke
				(width 0)
				(type default)
			)
			(fill no)
			(layer "F.CrtYd")
		)
		(pad "1" smd rect
			(at 0.40005 0)
			(size 0.4572 0.508)
			(layers "F.Cu" "F.Mask" "F.Paste")
			(net "P5V_STB_NODE1_EN")
		)
		(pad "2" smd rect
			(at -0.40005 0)
			(size 0.4572 0.508)
			(layers "F.Cu" "F.Mask" "F.Paste")
			(net "P12V_AUX")
		)
	)
	(footprint ""
		(layer "F.Cu")
		(at 94.451932 -172.268388)
		(property "Reference" "C575"
			(at 86.67369 74.174096 0)
			(unlocked yes)
			(layer "F.SilkS")
			(effects
				(font
					(size 0.7874 0.5842)
					(thickness 0.1524)
				)
				(justify left)
			)
		)
		(property "Value" ""
			(at 0 0 0)
			(layer "F.Fab")
			(effects
				(font
					(size 1.27 1.27)
				)
			)
		)
		(duplicate_pad_numbers_are_jumpers no)
		(fp_line
			(start -0.7874 -0.4064)
			(end 0.7874 -0.4064)
			(stroke
				(width 0.1524)
				(type default)
			)
			(layer "F.SilkS")
		)
		(fp_line
			(start -0.7874 0.4064)
			(end -0.7874 -0.4064)
			(stroke
				(width 0.1524)
				(type default)
			)
			(layer "F.SilkS")
		)
		(fp_line
			(start 0 0.381)
			(end 0 -0.381)
			(stroke
				(width 0.1524)
				(type default)
			)
			(layer "F.SilkS")
		)
		(fp_line
			(start 0.7874 -0.4064)
			(end 0.7874 0.4064)
			(stroke
				(width 0.1524)
				(type default)
			)
			(layer "F.SilkS")
		)
		(fp_line
			(start 0.7874 0.4064)
			(end -0.7874 0.4064)
			(stroke
				(width 0.1524)
				(type default)
			)
			(layer "F.SilkS")
		)
		(fp_poly
			(pts
				(xy -0.5334 0.254) (xy -0.635 0.254) (xy -0.635 0.2286) (xy -0.635 -0.254) (xy -0.5334 -0.254) (xy -0.5334 -0.2794)
				(xy 0.5334 -0.2794) (xy 0.5334 -0.254) (xy 0.635 -0.254) (xy 0.635 0.254) (xy 0.5334 0.254) (xy 0.5334 0.2794)
				(xy -0.508 0.2794) (xy -0.5334 0.2794)
			)
			(stroke
				(width 0)
				(type default)
			)
			(fill no)
			(layer "F.CrtYd")
		)
		(pad "1" smd rect
			(at 0.40005 0)
			(size 0.4572 0.508)
			(layers "F.Cu" "F.Mask" "F.Paste")
			(net "P3V3_NODE1")
		)
		(pad "2" smd rect
			(at -0.40005 0)
			(size 0.4572 0.508)
			(layers "F.Cu" "F.Mask" "F.Paste")
			(net "GND")
		)
	)
	(footprint ""
		(layer "F.Cu")
		(at 115.04676 -188.126624 90)
		(property "Reference" "C757"
			(at 5.151882 0.485902 90)
			(unlocked yes)
			(layer "F.SilkS")
			(effects
				(font
					(size 0.7874 0.5842)
					(thickness 0.1524)
				)
				(justify left)
			)
		)
		(property "Value" ""
			(at 0 0 90)
			(layer "F.Fab")
			(effects
				(font
					(size 1.27 1.27)
				)
			)
		)
		(duplicate_pad_numbers_are_jumpers no)
		(fp_line
			(start 0.7874 -0.4064)
			(end 0.7874 0.4064)
			(stroke
				(width 0.1524)
				(type default)
			)
			(layer "F.SilkS")
		)
		(fp_line
			(start -0.7874 -0.4064)
			(end 0.7874 -0.4064)
			(stroke
				(width 0.1524)
				(type default)
			)
			(layer "F.SilkS")
		)
		(fp_line
			(start 0 0.381)
			(end 0 -0.381)
			(stroke
				(width 0.1524)
				(type default)
			)
			(layer "F.SilkS")
		)
		(fp_line
			(start 0.7874 0.4064)
			(end -0.7874 0.4064)
			(stroke
				(width 0.1524)
				(type default)
			)
			(layer "F.SilkS")
		)
		(fp_line
			(start -0.7874 0.4064)
			(end -0.7874 -0.4064)
			(stroke
				(width 0.1524)
				(type default)
			)
			(layer "F.SilkS")
		)
		(fp_poly
			(pts
				(xy -0.5334 0.254) (xy -0.635 0.254) (xy -0.635 0.2286) (xy -0.635 -0.254) (xy -0.5334 -0.254) (xy -0.5334 -0.2794)
				(xy 0.5334 -0.2794) (xy 0.5334 -0.254) (xy 0.635 -0.254) (xy 0.635 0.254) (xy 0.5334 0.254) (xy 0.5334 0.2794)
				(xy -0.508 0.2794) (xy -0.5334 0.2794)
			)
			(stroke
				(width 0)
				(type default)
			)
			(fill no)
			(layer "F.CrtYd")
		)
		(pad "1" smd rect
			(at 0.40005 0 90)
			(size 0.4572 0.508)
			(layers "F.Cu" "F.Mask" "F.Paste")
			(net "UART_T8_NODE3_TXD_R")
		)
		(pad "2" smd rect
			(at -0.40005 0 90)
			(size 0.4572 0.508)
			(layers "F.Cu" "F.Mask" "F.Paste")
			(net "GND")
		)
	)
	(footprint ""
		(layer "F.Cu")
		(at 84.82076 -185.205624 -90)
		(property "Reference" "R824"
			(at -4.198112 1.945132 90)
			(unlocked yes)
			(layer "F.SilkS")
			(effects
				(font
					(size 0.7874 0.5842)
					(thickness 0.1524)
				)
				(justify left)
			)
		)
		(property "Value" ""
			(at 0 0 270)
			(layer "F.Fab")
			(effects
				(font
					(size 1.27 1.27)
				)
			)
		)
		(duplicate_pad_numbers_are_jumpers no)
		(fp_line
			(start -0.7874 0.4064)
			(end -0.7874 -0.4064)
			(stroke
				(width 0.1524)
				(type default)
			)
			(layer "F.SilkS")
		)
		(fp_line
			(start 0.7874 0.4064)
			(end -0.7874 0.4064)
			(stroke
				(width 0.1524)
				(type default)
			)
			(layer "F.SilkS")
		)
		(fp_line
			(start -0.7874 -0.4064)
			(end 0.7874 -0.4064)
			(stroke
				(width 0.1524)
				(type default)
			)
			(layer "F.SilkS")
		)
		(fp_line
			(start 0.7874 -0.4064)
			(end 0.7874 0.4064)
			(stroke
				(width 0.1524)
				(type default)
			)
			(layer "F.SilkS")
		)
		(fp_poly
			(pts
				(xy -0.508 0.2794) (xy -0.508 0.2286) (xy -0.635 0.2286) (xy -0.635 -0.254) (xy -0.5334 -0.254)
				(xy -0.5334 -0.2794) (xy 0.5334 -0.2794) (xy 0.5334 -0.254) (xy 0.635 -0.254) (xy 0.635 0.254) (xy 0.5334 0.254)
				(xy 0.5334 0.2794)
			)
			(stroke
				(width 0)
				(type default)
			)
			(fill no)
			(layer "F.CrtYd")
		)
		(pad "1" smd rect
			(at 0.40005 0 270)
			(size 0.4572 0.508)
			(layers "F.Cu" "F.Mask" "F.Paste")
			(net "I2C_PSU2_SCL")
		)
		(pad "2" smd rect
			(at -0.40005 0 270)
			(size 0.4572 0.508)
			(layers "F.Cu" "F.Mask" "F.Paste")
			(net "I2C_PSU2_R_SCL")
		)
	)
	(footprint ""
		(layer "F.Cu")
		(at 87.374984 -81.907888 180)
		(property "Reference" "C79"
			(at -1.232916 0.06858 0)
			(unlocked yes)
			(layer "F.SilkS")
			(effects
				(font
					(size 0.7874 0.5842)
					(thickness 0.1524)
				)
				(justify left)
			)
		)
		(property "Value" ""
			(at 0 0 180)
			(layer "F.Fab")
			(effects
				(font
					(size 1.27 1.27)
				)
			)
		)
		(duplicate_pad_numbers_are_jumpers no)
		(fp_line
			(start 0.7874 0.4064)
			(end -0.7874 0.4064)
			(stroke
				(width 0.1524)
				(type default)
			)
			(layer "F.SilkS")
		)
		(fp_line
			(start 0.7874 -0.4064)
			(end 0.7874 0.4064)
			(stroke
				(width 0.1524)
				(type default)
			)
			(layer "F.SilkS")
		)
		(fp_line
			(start 0 0.381)
			(end 0 -0.381)
			(stroke
				(width 0.1524)
				(type default)
			)
			(layer "F.SilkS")
		)
		(fp_line
			(start -0.7874 0.4064)
			(end -0.7874 -0.4064)
			(stroke
				(width 0.1524)
				(type default)
			)
			(layer "F.SilkS")
		)
		(fp_line
			(start -0.7874 -0.4064)
			(end 0.7874 -0.4064)
			(stroke
				(width 0.1524)
				(type default)
			)
			(layer "F.SilkS")
		)
		(fp_poly
			(pts
				(xy -0.5334 0.254) (xy -0.635 0.254) (xy -0.635 0.2286) (xy -0.635 -0.254) (xy -0.5334 -0.254) (xy -0.5334 -0.2794)
				(xy 0.5334 -0.2794) (xy 0.5334 -0.254) (xy 0.635 -0.254) (xy 0.635 0.254) (xy 0.5334 0.254) (xy 0.5334 0.2794)
				(xy -0.508 0.2794) (xy -0.5334 0.2794)
			)
			(stroke
				(width 0)
				(type default)
			)
			(fill no)
			(layer "F.CrtYd")
		)
		(pad "1" smd rect
			(at 0.40005 0 180)
			(size 0.4572 0.508)
			(layers "F.Cu" "F.Mask" "F.Paste")
			(net "P1V05_VCCPLLCPU1SIO_NODE1")
		)
		(pad "2" smd rect
			(at -0.40005 0 180)
			(size 0.4572 0.508)
			(layers "F.Cu" "F.Mask" "F.Paste")
			(net "GND")
		)
	)
)
